(kicad_pcb
	(version 20241229)
	(generator "pcbnew")
	(generator_version "9.0")
	(general
		(thickness 1.61)
		(legacy_teardrops no)
	)
	(paper "A3")
	(title_block
		(title "RDIMM DDR5 Tester")
		(date "2026-05-21")
		(rev "2.2.0")
		(company "Antmicro")
		(comment 9 "footprints 613-617 of 796")
	)
	(layers
		(0 "F.Cu" signal)
		(4 "In1.Cu" power)
		(6 "In2.Cu" mixed)
		(8 "In3.Cu" power)
		(10 "In4.Cu" mixed)
		(12 "In5.Cu" power)
		(14 "In6.Cu" mixed)
		(16 "In7.Cu" power)
		(18 "In8.Cu" power)
		(20 "In9.Cu" mixed)
		(22 "In10.Cu" power)
		(2 "B.Cu" signal)
		(9 "F.Adhes" user "F.Adhesive")
		(11 "B.Adhes" user "B.Adhesive")
		(13 "F.Paste" user)
		(15 "B.Paste" user)
		(5 "F.SilkS" user "F.Silkscreen")
		(7 "B.SilkS" user "B.Silkscreen")
		(1 "F.Mask" user)
		(3 "B.Mask" user)
		(17 "Dwgs.User" user "User.Drawings")
		(19 "Cmts.User" user "User.Comments")
		(21 "Eco1.User" user "User.Eco1")
		(23 "Eco2.User" user "User.Eco2")
		(25 "Edge.Cuts" user)
		(27 "Margin" user)
		(31 "F.CrtYd" user "F.Courtyard")
		(29 "B.CrtYd" user "B.Courtyard")
		(35 "F.Fab" user)
		(33 "B.Fab" user)
	)
	(footprint "antmicro-footprints:C_0402_1005Metric_EIA"
		(layer "B.Cu")
		(at 186 154.500001 90)
		(descr "Capacitor SMD 0402 (1005 Metric), square (rectangular) end terminal, IPC_7351 nominal, (Body size source: IPC-SM-782 page 76, https://www.pcb-3d.com/wordpress/wp-content/uploads/ipc-sm-782a_amendment_1_and_2.pdf)")
		(tags "capacitor 0402")
		(property "Reference" "C43"
			(at 9.950001 -30.675 90)
			(layer "B.SilkS")
			(effects
				(font
					(size 0.7 0.7)
					(thickness 0.15)
				)
				(justify right bottom mirror)
			)
		)
		(property "Value" "C_1u_25V_0402"
			(at 0 -1.169 90)
			(layer "B.Fab")
			(effects
				(font
					(size 0.7 0.7)
					(thickness 0.15)
				)
				(justify right bottom mirror)
			)
		)
		(property "Datasheet" "https://www.murata.com/products/productdetail?partno=GRM155R61E105KE11%23"
			(at 0 0 90)
			(layer "F.Fab")
			(hide yes)
			(effects
				(font
					(size 1.27 1.27)
					(thickness 0.15)
				)
			)
		)
		(property "MPN" "GRM155R61E105KE11J"
			(at 0 0 90)
			(unlocked yes)
			(layer "B.Fab")
			(hide yes)
			(effects
				(font
					(size 1 1)
					(thickness 0.15)
				)
				(justify mirror)
			)
		)
		(property "Manufacturer" "Murata"
			(at 0 0 90)
			(unlocked yes)
			(layer "B.Fab")
			(hide yes)
			(effects
				(font
					(size 1 1)
					(thickness 0.15)
				)
				(justify mirror)
			)
		)
		(property "License" "Apache-2.0"
			(at 0 0 90)
			(unlocked yes)
			(layer "B.Fab")
			(hide yes)
			(effects
				(font
					(size 1 1)
					(thickness 0.15)
				)
				(justify mirror)
			)
		)
		(property "Author" "Antmicro"
			(at 0 0 90)
			(unlocked yes)
			(layer "B.Fab")
			(hide yes)
			(effects
				(font
					(size 1 1)
					(thickness 0.15)
				)
				(justify mirror)
			)
		)
		(property "Val" "1u"
			(at 0 0 90)
			(unlocked yes)
			(layer "B.Fab")
			(hide yes)
			(effects
				(font
					(size 1 1)
					(thickness 0.15)
				)
				(justify mirror)
			)
		)
		(property "Voltage" "25V"
			(at 0 0 90)
			(unlocked yes)
			(layer "B.Fab")
			(hide yes)
			(effects
				(font
					(size 1 1)
					(thickness 0.15)
				)
				(justify mirror)
			)
		)
		(property "Dielectric" "X5R"
			(at 0 0 90)
			(unlocked yes)
			(layer "B.Fab")
			(hide yes)
			(effects
				(font
					(size 1 1)
					(thickness 0.15)
				)
				(justify mirror)
			)
		)
		(sheetname "/FPGA power/")
		(sheetfile "fpga-power.kicad_sch")
		(attr smd)
		(fp_rect
			(start -0.95 0.45)
			(end 0.95 -0.45)
			(stroke
				(width 0.05)
				(type default)
			)
			(fill no)
			(layer "B.CrtYd")
		)
		(fp_line
			(start 0.498 -0.248)
			(end -0.5 -0.248)
			(stroke
				(width 0.15)
				(type solid)
			)
			(layer "B.Fab")
		)
		(fp_line
			(start -0.5 -0.248)
			(end -0.5 0.25)
			(stroke
				(width 0.15)
				(type solid)
			)
			(layer "B.Fab")
		)
		(fp_line
			(start 0.498 0.25)
			(end 0.498 -0.248)
			(stroke
				(width 0.15)
				(type solid)
			)
			(layer "B.Fab")
		)
		(fp_line
			(start -0.5 0.25)
			(end 0.498 0.25)
			(stroke
				(width 0.15)
				(type solid)
			)
			(layer "B.Fab")
		)
		(fp_text user "Author: Antmicro"
			(at -0.9656 -5.569 270)
			(layer "B.Fab")
			(effects
				(font
					(size 0.7 0.7)
					(thickness 0.15)
				)
				(justify left bottom mirror)
			)
		)
		(fp_text user "${REFERENCE}"
			(at -0.9656 -3.169 270)
			(layer "B.Fab")
			(effects
				(font
					(size 0.7 0.7)
					(thickness 0.15)
				)
				(justify left bottom mirror)
			)
		)
		(fp_text user "License: Apache-2.0"
			(at -0.9656 -4.369 270)
			(layer "B.Fab")
			(effects
				(font
					(size 0.7 0.7)
					(thickness 0.15)
				)
				(justify left bottom mirror)
			)
		)
		(pad "1" smd roundrect
			(at -0.5 0)
			(size 0.6 0.6)
			(layers "B.Cu" "B.Mask" "B.Paste")
			(roundrect_rratio 0.25)
			(net 1 "GND")
			(pintype "passive")
		)
		(pad "2" smd roundrect
			(at 0.498 0 90)
			(size 0.6 0.6)
			(layers "B.Cu" "B.Mask" "B.Paste")
			(roundrect_rratio 0.25)
			(net 553 "+0V85")
			(pintype "passive")
		)
	)
	(footprint "antmicro-footprints:C_0402_1005Metric"
		(layer "B.Cu")
		(at 122.95 149.61)
		(descr "Capacitor SMD 0402")
		(tags "capacitor SMD 0402")
		(property "Reference" "C305"
			(at 2.31 1.262 0)
			(layer "B.SilkS")
			(effects
				(font
					(size 0.7 0.7)
					(thickness 0.15)
				)
				(justify right bottom mirror)
			)
		)
		(property "Value" "C_100n_0402"
			(at -1.022927 -2.155213 0)
			(layer "B.Fab")
			(effects
				(font
					(size 0.7 0.7)
					(thickness 0.15)
				)
				(justify right bottom mirror)
			)
		)
		(property "Datasheet" "https://www.murata.com/products/productdetail?partno=GRM155R61H104KE14%23"
			(at 0 0 0)
			(layer "F.Fab")
			(hide yes)
			(effects
				(font
					(size 1.27 1.27)
					(thickness 0.15)
				)
			)
		)
		(property "Manufacturer" "Murata"
			(at 0 0 0)
			(unlocked yes)
			(layer "B.Fab")
			(hide yes)
			(effects
				(font
					(size 1 1)
					(thickness 0.15)
				)
				(justify mirror)
			)
		)
		(property "MPN" "GRM155R61H104KE14D"
			(at 0 0 0)
			(unlocked yes)
			(layer "B.Fab")
			(hide yes)
			(effects
				(font
					(size 1 1)
					(thickness 0.15)
				)
				(justify mirror)
			)
		)
		(property "Val" "100n"
			(at 0 0 0)
			(unlocked yes)
			(layer "B.Fab")
			(hide yes)
			(effects
				(font
					(size 1 1)
					(thickness 0.15)
				)
				(justify mirror)
			)
		)
		(property "License" "Apache-2.0"
			(at 0 0 0)
			(unlocked yes)
			(layer "B.Fab")
			(hide yes)
			(effects
				(font
					(size 1 1)
					(thickness 0.15)
				)
				(justify mirror)
			)
		)
		(property "Author" "Antmicro"
			(at 0 0 0)
			(unlocked yes)
			(layer "B.Fab")
			(hide yes)
			(effects
				(font
					(size 1 1)
					(thickness 0.15)
				)
				(justify mirror)
			)
		)
		(property "Voltage" "50V"
			(at 0 0 0)
			(unlocked yes)
			(layer "B.Fab")
			(hide yes)
			(effects
				(font
					(size 1 1)
					(thickness 0.15)
				)
				(justify mirror)
			)
		)
		(property "Dielectric" "X5R"
			(at 0 0 0)
			(unlocked yes)
			(layer "B.Fab")
			(hide yes)
			(effects
				(font
					(size 1 1)
					(thickness 0.15)
				)
				(justify mirror)
			)
		)
		(sheetname "/FPGA MGT Interface/")
		(sheetfile "fpga-mgt.kicad_sch")
		(attr smd)
		(fp_rect
			(start -0.925 0.47)
			(end 0.925 -0.47)
			(stroke
				(width 0.05)
				(type default)
			)
			(fill no)
			(layer "B.CrtYd")
		)
		(fp_line
			(start -0.494 -0.248)
			(end -0.494 0.25)
			(stroke
				(width 0.15)
				(type solid)
			)
			(layer "B.Fab")
		)
		(fp_line
			(start -0.494 0.25)
			(end 0.504 0.25)
			(stroke
				(width 0.15)
				(type solid)
			)
			(layer "B.Fab")
		)
		(fp_line
			(start 0.504 -0.248)
			(end -0.494 -0.248)
			(stroke
				(width 0.15)
				(type solid)
			)
			(layer "B.Fab")
		)
		(fp_line
			(start 0.504 0.25)
			(end 0.504 -0.248)
			(stroke
				(width 0.15)
				(type solid)
			)
			(layer "B.Fab")
		)
		(fp_text user "Author: Antmicro"
			(at -0.939 -3.399 180)
			(layer "B.Fab")
			(effects
				(font
					(size 0.7 0.7)
					(thickness 0.15)
				)
				(justify left bottom mirror)
			)
		)
		(fp_text user "${REFERENCE}"
			(at -0.939 -4.599 180)
			(layer "B.Fab")
			(effects
				(font
					(size 0.7 0.7)
					(thickness 0.15)
				)
				(justify left bottom mirror)
			)
		)
		(fp_text user "License: Apache-2.0"
			(at -0.939 -5.799 180)
			(layer "B.Fab")
			(effects
				(font
					(size 0.7 0.7)
					(thickness 0.15)
				)
				(justify left bottom mirror)
			)
		)
		(pad "1" smd roundrect
			(at -0.48 0)
			(size 0.59 0.64)
			(layers "B.Cu" "B.Mask" "B.Paste")
			(roundrect_rratio 0.25)
			(net 348 "/FPGA MGT Interface/HDMI_IN.D1_P")
			(pintype "passive")
		)
		(pad "2" smd roundrect
			(at 0.48 0)
			(size 0.59 0.64)
			(layers "B.Cu" "B.Mask" "B.Paste")
			(roundrect_rratio 0.25)
			(net 651 "/FPGA MGT Interface/HDMI_FPGA.RX1_P")
			(pintype "passive")
		)
	)
	(footprint "antmicro-footprints:C_0805_2012Metric"
		(layer "B.Cu")
		(at 183.35 152.525)
		(descr "Capacitor SMD 0805")
		(tags "capacitor SMD 0805")
		(property "Reference" "C38"
			(at -32.2 -10.425 0)
			(layer "B.SilkS")
			(effects
				(font
					(size 0.7 0.7)
					(thickness 0.15)
				)
				(justify right bottom mirror)
			)
		)
		(property "Value" "C_100u_0805"
			(at -2.055717 -1.963152 0)
			(layer "B.Fab")
			(effects
				(font
					(size 0.7 0.7)
					(thickness 0.15)
				)
				(justify right bottom mirror)
			)
		)
		(property "Datasheet" "https://www.murata.com/products/productdetail?partno=GRM21BR60J107ME15%23"
			(at 0 0 0)
			(layer "F.Fab")
			(hide yes)
			(effects
				(font
					(size 1.27 1.27)
					(thickness 0.15)
				)
			)
		)
		(property "MPN" "GRM21BR60J107ME15L"
			(at 0 0 0)
			(unlocked yes)
			(layer "B.Fab")
			(hide yes)
			(effects
				(font
					(size 1 1)
					(thickness 0.15)
				)
				(justify mirror)
			)
		)
		(property "Manufacturer" "Murata"
			(at 0 0 0)
			(unlocked yes)
			(layer "B.Fab")
			(hide yes)
			(effects
				(font
					(size 1 1)
					(thickness 0.15)
				)
				(justify mirror)
			)
		)
		(property "License" "Apache-2.0"
			(at 0 0 0)
			(unlocked yes)
			(layer "B.Fab")
			(hide yes)
			(effects
				(font
					(size 1 1)
					(thickness 0.15)
				)
				(justify mirror)
			)
		)
		(property "Author" "Antmicro"
			(at 0 0 0)
			(unlocked yes)
			(layer "B.Fab")
			(hide yes)
			(effects
				(font
					(size 1 1)
					(thickness 0.15)
				)
				(justify mirror)
			)
		)
		(property "Val" "100u"
			(at 0 0 0)
			(unlocked yes)
			(layer "B.Fab")
			(hide yes)
			(effects
				(font
					(size 1 1)
					(thickness 0.15)
				)
				(justify mirror)
			)
		)
		(property "Voltage" ""
			(at 0 0 0)
			(unlocked yes)
			(layer "B.Fab")
			(hide yes)
			(effects
				(font
					(size 1 1)
					(thickness 0.15)
				)
				(justify mirror)
			)
		)
		(property "Dielectric" ""
			(at 0 0 0)
			(unlocked yes)
			(layer "B.Fab")
			(hide yes)
			(effects
				(font
					(size 1 1)
					(thickness 0.15)
				)
				(justify mirror)
			)
		)
		(property "Public" "False"
			(at 0 0 0)
			(unlocked yes)
			(layer "B.Fab")
			(hide yes)
			(effects
				(font
					(size 1 1)
					(thickness 0.15)
				)
				(justify mirror)
			)
		)
		(sheetname "/FPGA power/")
		(sheetfile "fpga-power.kicad_sch")
		(attr smd)
		(fp_line
			(start -0.3 -0.7)
			(end 0.3 -0.7)
			(stroke
				(width 0.15)
				(type solid)
			)
			(layer "B.SilkS")
		)
		(fp_line
			(start -0.3 0.7)
			(end 0.3 0.7)
			(stroke
				(width 0.15)
				(type solid)
			)
			(layer "B.SilkS")
		)
		(fp_rect
			(start 1.95 0.9)
			(end -1.95 -0.9)
			(stroke
				(width 0.05)
				(type default)
			)
			(fill no)
			(layer "B.CrtYd")
		)
		(fp_rect
			(start -0.95 0.675)
			(end 0.95 -0.675)
			(stroke
				(width 0.15)
				(type solid)
			)
			(fill no)
			(layer "B.Fab")
		)
		(fp_text user "License: Apache-2.0"
			(at -1.9 -4.947 180)
			(layer "B.Fab")
			(effects
				(font
					(size 0.7 0.7)
					(thickness 0.15)
				)
				(justify left bottom mirror)
			)
		)
		(fp_text user "${REFERENCE}"
			(at -1.9 -3.947 180)
			(layer "B.Fab")
			(effects
				(font
					(size 0.7 0.7)
					(thickness 0.15)
				)
				(justify left bottom mirror)
			)
		)
		(fp_text user "Author: Antmicro"
			(at -1.9 -5.947 180)
			(layer "B.Fab")
			(effects
				(font
					(size 0.7 0.7)
					(thickness 0.15)
				)
				(justify left bottom mirror)
			)
		)
		(pad "1" smd roundrect
			(at -1.1 0)
			(size 1.2 1.3)
			(layers "B.Cu" "B.Mask" "B.Paste")
			(roundrect_rratio 0.25)
			(net 1 "GND")
			(pintype "passive")
		)
		(pad "2" smd roundrect
			(at 1.1 0)
			(size 1.2 1.3)
			(layers "B.Cu" "B.Mask" "B.Paste")
			(roundrect_rratio 0.25)
			(net 553 "+0V85")
			(pintype "passive")
		)
	)
	(footprint "antmicro-footprints:C_0603_1608Metric"
		(layer "B.Cu")
		(at 248.32 121.47 90)
		(descr "Capacitor SMD 0603")
		(tags "capacitor 0603")
		(property "Reference" "C326"
			(at -4.11 0.48 90)
			(layer "B.SilkS")
			(effects
				(font
					(size 0.7 0.7)
					(thickness 0.15)
				)
				(justify right bottom mirror)
			)
		)
		(property "Value" "C_10u_25V_0603"
			(at -1.42757 -1.770288 90)
			(layer "B.Fab")
			(effects
				(font
					(size 0.7 0.7)
					(thickness 0.15)
				)
				(justify right bottom mirror)
			)
		)
		(property "Datasheet" "https://product.tdk.com/en/search/capacitor/ceramic/mlcc/info?part_no=C1608X5R1E106M080AC"
			(at 0 0 90)
			(layer "F.Fab")
			(hide yes)
			(effects
				(font
					(size 1.27 1.27)
					(thickness 0.15)
				)
			)
		)
		(property "MPN" "C1608X5R1E106M080AC"
			(at 0 0 90)
			(unlocked yes)
			(layer "B.Fab")
			(hide yes)
			(effects
				(font
					(size 1 1)
					(thickness 0.15)
				)
				(justify mirror)
			)
		)
		(property "Manufacturer" "TDK"
			(at 0 0 90)
			(unlocked yes)
			(layer "B.Fab")
			(hide yes)
			(effects
				(font
					(size 1 1)
					(thickness 0.15)
				)
				(justify mirror)
			)
		)
		(property "License" "Apache-2.0"
			(at 0 0 90)
			(unlocked yes)
			(layer "B.Fab")
			(hide yes)
			(effects
				(font
					(size 1 1)
					(thickness 0.15)
				)
				(justify mirror)
			)
		)
		(property "Author" "Antmicro"
			(at 0 0 90)
			(unlocked yes)
			(layer "B.Fab")
			(hide yes)
			(effects
				(font
					(size 1 1)
					(thickness 0.15)
				)
				(justify mirror)
			)
		)
		(property "Val" "10u"
			(at 0 0 90)
			(unlocked yes)
			(layer "B.Fab")
			(hide yes)
			(effects
				(font
					(size 1 1)
					(thickness 0.15)
				)
				(justify mirror)
			)
		)
		(property "Voltage" "25V"
			(at 0 0 90)
			(unlocked yes)
			(layer "B.Fab")
			(hide yes)
			(effects
				(font
					(size 1 1)
					(thickness 0.15)
				)
				(justify mirror)
			)
		)
		(property "Dielectric" ""
			(at 0 0 90)
			(unlocked yes)
			(layer "B.Fab")
			(hide yes)
			(effects
				(font
					(size 1 1)
					(thickness 0.15)
				)
				(justify mirror)
			)
		)
		(sheetname "/Supply/")
		(sheetfile "supply.kicad_sch")
		(attr smd)
		(fp_line
			(start -0.15 -0.4)
			(end 0.15 -0.4)
			(stroke
				(width 0.15)
				(type solid)
			)
			(layer "B.SilkS")
		)
		(fp_line
			(start -0.15 0.4)
			(end 0.15 0.4)
			(stroke
				(width 0.15)
				(type solid)
			)
			(layer "B.SilkS")
		)
		(fp_rect
			(start -1.25 0.65)
			(end 1.25 -0.65)
			(stroke
				(width 0.05)
				(type solid)
			)
			(fill no)
			(layer "B.CrtYd")
		)
		(fp_rect
			(start -0.8 0.4)
			(end 0.8 -0.4)
			(stroke
				(width 0.15)
				(type solid)
			)
			(fill no)
			(layer "B.Fab")
		)
		(fp_text user "${REFERENCE}"
			(at -1.682 -3.895 270)
			(layer "B.Fab")
			(effects
				(font
					(size 0.7 0.7)
					(thickness 0.15)
				)
				(justify left bottom mirror)
			)
		)
		(fp_text user "License: Apache-2.0"
			(at -1.682 -5.895 270)
			(layer "B.Fab")
			(effects
				(font
					(size 0.7 0.7)
					(thickness 0.15)
				)
				(justify left bottom mirror)
			)
		)
		(fp_text user "Author: Antmicro"
			(at -1.682 -4.894 270)
			(layer "B.Fab")
			(effects
				(font
					(size 0.7 0.7)
					(thickness 0.15)
				)
				(justify left bottom mirror)
			)
		)
		(pad "1" smd roundrect
			(at -0.7 0 90)
			(size 0.8 1)
			(layers "B.Cu" "B.Mask" "B.Paste")
			(roundrect_rratio 0.2)
			(net 1 "GND")
			(pintype "passive")
		)
		(pad "2" smd roundrect
			(at 0.7 0 90)
			(size 0.8 1)
			(layers "B.Cu" "B.Mask" "B.Paste")
			(roundrect_rratio 0.2)
			(net 35 "VDC")
			(pintype "passive")
		)
	)
	(footprint "antmicro-footprints:C_0402_1005Metric"
		(layer "B.Cu")
		(at 207.321 136.0045)
		(descr "Capacitor SMD 0402")
		(tags "capacitor SMD 0402")
		(property "Reference" "C331"
			(at 2.279 0 0)
			(layer "B.SilkS")
			(effects
				(font
					(size 0.7 0.7)
					(thickness 0.15)
				)
				(justify mirror)
			)
		)
		(property "Value" "C_10u_6.3V_0402"
			(at -1.022927 -2.155213 0)
			(layer "B.Fab")
			(effects
				(font
					(size 0.7 0.7)
					(thickness 0.15)
				)
				(justify right top mirror)
			)
		)
		(property "Datasheet" "https://www.murata.com/products/productdetail?partno=GRM155R60J106ME15%23"
			(at 0 0 0)
			(layer "B.Fab")
			(hide yes)
			(effects
				(font
					(size 1.27 1.27)
					(thickness 0.15)
				)
				(justify mirror)
			)
		)
		(property "MPN" "GRM155R60J106ME15D"
			(at 0 0 180)
			(unlocked yes)
			(layer "B.Fab")
			(hide yes)
			(effects
				(font
					(size 1 1)
					(thickness 0.15)
				)
				(justify mirror)
			)
		)
		(property "Manufacturer" "Murata"
			(at 0 0 180)
			(unlocked yes)
			(layer "B.Fab")
			(hide yes)
			(effects
				(font
					(size 1 1)
					(thickness 0.15)
				)
				(justify mirror)
			)
		)
		(property "License" "Apache-2.0"
			(at 0 0 180)
			(unlocked yes)
			(layer "B.Fab")
			(hide yes)
			(effects
				(font
					(size 1 1)
					(thickness 0.15)
				)
				(justify mirror)
			)
		)
		(property "Author" "Antmicro"
			(at 0 0 180)
			(unlocked yes)
			(layer "B.Fab")
			(hide yes)
			(effects
				(font
					(size 1 1)
					(thickness 0.15)
				)
				(justify mirror)
			)
		)
		(property "Val" "10u"
			(at 0 0 180)
			(unlocked yes)
			(layer "B.Fab")
			(hide yes)
			(effects
				(font
					(size 1 1)
					(thickness 0.15)
				)
				(justify mirror)
			)
		)
		(property "Voltage" "6.3V"
			(at 0 0 180)
			(unlocked yes)
			(layer "B.Fab")
			(hide yes)
			(effects
				(font
					(size 1 1)
					(thickness 0.15)
				)
				(justify mirror)
			)
		)
		(property "Dielectric" "X5R"
			(at 0 0 180)
			(unlocked yes)
			(layer "B.Fab")
			(hide yes)
			(effects
				(font
					(size 1 1)
					(thickness 0.15)
				)
				(justify mirror)
			)
		)
		(sheetname "/Supply/")
		(sheetfile "supply.kicad_sch")
		(attr smd)
		(fp_rect
			(start -0.925 0.47)
			(end 0.925 -0.47)
			(stroke
				(width 0.05)
				(type default)
			)
			(fill no)
			(layer "B.CrtYd")
		)
		(fp_line
			(start -0.494 -0.248)
			(end -0.494 0.25)
			(stroke
				(width 0.15)
				(type solid)
			)
			(layer "B.Fab")
		)
		(fp_line
			(start -0.494 0.25)
			(end 0.504 0.25)
			(stroke
				(width 0.15)
				(type solid)
			)
			(layer "B.Fab")
		)
		(fp_line
			(start 0.504 -0.248)
			(end -0.494 -0.248)
			(stroke
				(width 0.15)
				(type solid)
			)
			(layer "B.Fab")
		)
		(fp_line
			(start 0.504 0.25)
			(end 0.504 -0.248)
			(stroke
				(width 0.15)
				(type solid)
			)
			(layer "B.Fab")
		)
		(fp_text user "Author: Antmicro"
			(at -0.939 -3.399 0)
			(layer "B.Fab")
			(effects
				(font
					(size 0.7 0.7)
					(thickness 0.15)
				)
				(justify right top mirror)
			)
		)
		(fp_text user "${REFERENCE}"
			(at -0.939 -4.599 0)
			(layer "B.Fab")
			(effects
				(font
					(size 0.7 0.7)
					(thickness 0.15)
				)
				(justify right top mirror)
			)
		)
		(fp_text user "License: Apache-2.0"
			(at -0.939 -5.799 0)
			(layer "B.Fab")
			(effects
				(font
					(size 0.7 0.7)
					(thickness 0.15)
				)
				(justify right top mirror)
			)
		)
		(pad "1" smd roundrect
			(at -0.48 0)
			(size 0.59 0.64)
			(layers "B.Cu" "B.Mask" "B.Paste")
			(roundrect_rratio 0.25)
			(net 1 "GND")
			(pintype "passive")
		)
		(pad "2" smd roundrect
			(at 0.48 0)
			(size 0.59 0.64)
			(layers "B.Cu" "B.Mask" "B.Paste")
			(roundrect_rratio 0.25)
			(net 687 "VDDQ")
			(pintype "passive")
		)
	)
)
